(kicad_pcb
	(version 20260206)
	(generator "pcbnew")
	(generator_version "10.0")
	(general
		(thickness 1.6)
		(legacy_teardrops no)
	)
	(paper "A4")
	(title_block
		(title "04192023_DAF0TMB3IC0_F0TG_MB_C_brd_V02_OCP.brd")
		(comment 1 "Grand Teton / footprints 2146-2152 of 8354")
	)
	(layers
		(0 "F.Cu" signal "TOP")
		(4 "In1.Cu" signal "GND")
		(6 "In2.Cu" signal "IN1")
		(8 "In3.Cu" signal "GND1")
		(10 "In4.Cu" signal "IN2")
		(12 "In5.Cu" signal "GND2")
		(14 "In6.Cu" signal "IN3")
		(16 "In7.Cu" signal "GND3")
		(18 "In8.Cu" signal "VCC")
		(20 "In9.Cu" signal "VCC1")
		(22 "In10.Cu" signal "GND4")
		(24 "In11.Cu" signal "IN4")
		(26 "In12.Cu" signal "GND5")
		(28 "In13.Cu" signal "IN5")
		(30 "In14.Cu" signal "GND6")
		(32 "In15.Cu" signal "IN6")
		(34 "In16.Cu" signal "GND7")
		(2 "B.Cu" signal "BOTTOM")
		(9 "F.Adhes" user "F.Adhesive")
		(11 "B.Adhes" user "B.Adhesive")
		(13 "F.Paste" user "Package Geometry/Pastemask Top")
		(15 "B.Paste" user "Package Geometry/Pastemask Bottom")
		(5 "F.SilkS" user "Ref Des/Silkscreen Top")
		(7 "B.SilkS" user "Ref Des/Silkscreen Bottom")
		(1 "F.Mask" user "Board Geometry/Soldermask Top")
		(3 "B.Mask" user "Board Geometry/Soldermask Bottom")
		(17 "Dwgs.User" user "User.Drawings")
		(19 "Cmts.User" user "User.Comments")
		(21 "Eco1.User" user "User.Eco1")
		(23 "Eco2.User" user "User.Eco2")
		(25 "Edge.Cuts" user "Board Geometry/Outline")
		(27 "Margin" user)
		(31 "F.CrtYd" user "Package Geometry/Place Bound Top")
		(29 "B.CrtYd" user "Package Geometry/Place Bound Bottom")
		(35 "F.Fab" user "Ref Des/Assembly Top")
		(33 "B.Fab" user "Ref Des/Assembly Bottom")
	)
	(footprint ""
		(layer "F.Cu")
		(at 166.070534 -21.783548 90)
		(property "Reference" "R87"
			(at 0 0 90)
			(layer "F.SilkS")
			(hide yes)
			(effects
				(font
					(size 1.27 1.27)
				)
			)
		)
		(property "Value" ""
			(at 0 0 90)
			(layer "F.Fab")
			(effects
				(font
					(size 1.27 1.27)
				)
			)
		)
		(duplicate_pad_numbers_are_jumpers no)
		(fp_line
			(start 0.7874 -0.4064)
			(end 0.7874 0.4064)
			(stroke
				(width 0.1524)
				(type default)
			)
			(layer "F.SilkS")
		)
		(fp_line
			(start -0.7874 -0.4064)
			(end 0.7874 -0.4064)
			(stroke
				(width 0.1524)
				(type default)
			)
			(layer "F.SilkS")
		)
		(fp_line
			(start 0.7874 0.4064)
			(end -0.7874 0.4064)
			(stroke
				(width 0.1524)
				(type default)
			)
			(layer "F.SilkS")
		)
		(fp_line
			(start -0.7874 0.4064)
			(end -0.7874 -0.4064)
			(stroke
				(width 0.1524)
				(type default)
			)
			(layer "F.SilkS")
		)
		(fp_line
			(start -0.12065 -0.305054)
			(end -0.12065 -0.2794)
			(stroke
				(width 0.1)
				(type default)
			)
			(layer "F.Fab")
		)
		(fp_line
			(start -0.67945 -0.305054)
			(end -0.12065 -0.305054)
			(stroke
				(width 0.1)
				(type default)
			)
			(layer "F.Fab")
		)
		(fp_line
			(start 0.67945 -0.3048)
			(end 0.67945 0.3048)
			(stroke
				(width 0.1)
				(type default)
			)
			(layer "F.Fab")
		)
		(fp_line
			(start 0.12065 -0.3048)
			(end 0.67945 -0.3048)
			(stroke
				(width 0.1)
				(type default)
			)
			(layer "F.Fab")
		)
		(fp_line
			(start 0.12065 -0.2794)
			(end 0.12065 -0.3048)
			(stroke
				(width 0.1)
				(type default)
			)
			(layer "F.Fab")
		)
		(fp_line
			(start -0.12065 -0.2794)
			(end 0.12065 -0.2794)
			(stroke
				(width 0.1)
				(type default)
			)
			(layer "F.Fab")
		)
		(fp_line
			(start 0.120396 0.2794)
			(end -0.12065 0.2794)
			(stroke
				(width 0.1)
				(type default)
			)
			(layer "F.Fab")
		)
		(fp_line
			(start -0.12065 0.2794)
			(end -0.12065 0.3048)
			(stroke
				(width 0.1)
				(type default)
			)
			(layer "F.Fab")
		)
		(fp_line
			(start 0.67945 0.3048)
			(end 0.120396 0.3048)
			(stroke
				(width 0.1)
				(type default)
			)
			(layer "F.Fab")
		)
		(fp_line
			(start 0.120396 0.3048)
			(end 0.120396 0.2794)
			(stroke
				(width 0.1)
				(type default)
			)
			(layer "F.Fab")
		)
		(fp_line
			(start -0.12065 0.3048)
			(end -0.67945 0.3048)
			(stroke
				(width 0.1)
				(type default)
			)
			(layer "F.Fab")
		)
		(fp_line
			(start -0.67945 0.3048)
			(end -0.67945 -0.305054)
			(stroke
				(width 0.1)
				(type default)
			)
			(layer "F.Fab")
		)
		(pad "1" smd circle
			(at -0.40005 0 90)
			(size 0 0)
			(layers "F.Cu" "F.Mask" "F.Paste")
			(net "RMII_BMC_OCP_RX_ER")
		)
		(pad "2" smd circle
			(at 0.40005 0 90)
			(size 0 0)
			(layers "F.Cu" "F.Mask" "F.Paste")
			(net "GND")
		)
	)
	(footprint ""
		(layer "F.Cu")
		(at 390.921748 -16.100298 90)
		(property "Reference" "C1549"
			(at 0 0 90)
			(layer "F.SilkS")
			(hide yes)
			(effects
				(font
					(size 1.27 1.27)
				)
			)
		)
		(property "Value" ""
			(at 0 0 90)
			(layer "F.Fab")
			(effects
				(font
					(size 1.27 1.27)
				)
			)
		)
		(duplicate_pad_numbers_are_jumpers no)
		(fp_line
			(start 0.299974 -0.150114)
			(end 0.299974 0.150114)
			(stroke
				(width 0.1)
				(type default)
			)
			(layer "F.Fab")
		)
		(fp_line
			(start -0.299974 -0.150114)
			(end 0.299974 -0.150114)
			(stroke
				(width 0.1)
				(type default)
			)
			(layer "F.Fab")
		)
		(fp_line
			(start 0.299974 0.150114)
			(end -0.299974 0.150114)
			(stroke
				(width 0.1)
				(type default)
			)
			(layer "F.Fab")
		)
		(fp_line
			(start -0.299974 0.150114)
			(end -0.299974 -0.150114)
			(stroke
				(width 0.1)
				(type default)
			)
			(layer "F.Fab")
		)
		(pad "1" smd rect
			(at -0.2667 0 90)
			(size 0.3048 0.381)
			(layers "F.Cu" "F.Mask" "F.Paste")
			(net "P5E_CPU0_G3_TX_C_DP<15>")
		)
		(pad "2" smd rect
			(at 0.2667 0 90)
			(size 0.3048 0.381)
			(layers "F.Cu" "F.Mask" "F.Paste")
			(net "P5E_CPU0_G3_TX_DP<15>")
		)
	)
	(footprint ""
		(layer "F.Cu")
		(at 319.105026 -339.647022 90)
		(property "Reference" "PR90"
			(at 0 0 90)
			(layer "F.SilkS")
			(hide yes)
			(effects
				(font
					(size 1.27 1.27)
				)
			)
		)
		(property "Value" ""
			(at 0 0 90)
			(layer "F.Fab")
			(effects
				(font
					(size 1.27 1.27)
				)
			)
		)
		(duplicate_pad_numbers_are_jumpers no)
		(fp_line
			(start 0.7874 -0.4064)
			(end 0.7874 0.4064)
			(stroke
				(width 0.1524)
				(type default)
			)
			(layer "F.SilkS")
		)
		(fp_line
			(start -0.7874 -0.4064)
			(end 0.7874 -0.4064)
			(stroke
				(width 0.1524)
				(type default)
			)
			(layer "F.SilkS")
		)
		(fp_line
			(start 0.7874 0.4064)
			(end -0.7874 0.4064)
			(stroke
				(width 0.1524)
				(type default)
			)
			(layer "F.SilkS")
		)
		(fp_line
			(start -0.7874 0.4064)
			(end -0.7874 -0.4064)
			(stroke
				(width 0.1524)
				(type default)
			)
			(layer "F.SilkS")
		)
		(fp_line
			(start -0.12065 -0.305054)
			(end -0.12065 -0.2794)
			(stroke
				(width 0.1)
				(type default)
			)
			(layer "F.Fab")
		)
		(fp_line
			(start -0.67945 -0.305054)
			(end -0.12065 -0.305054)
			(stroke
				(width 0.1)
				(type default)
			)
			(layer "F.Fab")
		)
		(fp_line
			(start 0.67945 -0.3048)
			(end 0.67945 0.3048)
			(stroke
				(width 0.1)
				(type default)
			)
			(layer "F.Fab")
		)
		(fp_line
			(start 0.12065 -0.3048)
			(end 0.67945 -0.3048)
			(stroke
				(width 0.1)
				(type default)
			)
			(layer "F.Fab")
		)
		(fp_line
			(start 0.12065 -0.2794)
			(end 0.12065 -0.3048)
			(stroke
				(width 0.1)
				(type default)
			)
			(layer "F.Fab")
		)
		(fp_line
			(start -0.12065 -0.2794)
			(end 0.12065 -0.2794)
			(stroke
				(width 0.1)
				(type default)
			)
			(layer "F.Fab")
		)
		(fp_line
			(start 0.120396 0.2794)
			(end -0.12065 0.2794)
			(stroke
				(width 0.1)
				(type default)
			)
			(layer "F.Fab")
		)
		(fp_line
			(start -0.12065 0.2794)
			(end -0.12065 0.3048)
			(stroke
				(width 0.1)
				(type default)
			)
			(layer "F.Fab")
		)
		(fp_line
			(start 0.67945 0.3048)
			(end 0.120396 0.3048)
			(stroke
				(width 0.1)
				(type default)
			)
			(layer "F.Fab")
		)
		(fp_line
			(start 0.120396 0.3048)
			(end 0.120396 0.2794)
			(stroke
				(width 0.1)
				(type default)
			)
			(layer "F.Fab")
		)
		(fp_line
			(start -0.12065 0.3048)
			(end -0.67945 0.3048)
			(stroke
				(width 0.1)
				(type default)
			)
			(layer "F.Fab")
		)
		(fp_line
			(start -0.67945 0.3048)
			(end -0.67945 -0.305054)
			(stroke
				(width 0.1)
				(type default)
			)
			(layer "F.Fab")
		)
		(pad "1" smd circle
			(at -0.40005 0 90)
			(size 0 0)
			(layers "F.Cu" "F.Mask" "F.Paste")
			(net "SW_PVDDCR_CPU1_P0_BOOT3")
		)
		(pad "2" smd circle
			(at 0.40005 0 90)
			(size 0 0)
			(layers "F.Cu" "F.Mask" "F.Paste")
			(net "SW_PVDDCR_CPU1_P0_BOOT3_R")
		)
	)
	(footprint ""
		(layer "F.Cu")
		(at 430.02835 -399.72488 180)
		(property "Reference" "R1058"
			(at 0 0 180)
			(layer "F.SilkS")
			(hide yes)
			(effects
				(font
					(size 1.27 1.27)
				)
			)
		)
		(property "Value" ""
			(at 0 0 180)
			(layer "F.Fab")
			(effects
				(font
					(size 1.27 1.27)
				)
			)
		)
		(duplicate_pad_numbers_are_jumpers no)
		(fp_line
			(start 0.32512 0.175006)
			(end -0.32512 0.175006)
			(stroke
				(width 0.1)
				(type default)
			)
			(layer "F.Fab")
		)
		(fp_line
			(start 0.32512 -0.175006)
			(end 0.32512 0.175006)
			(stroke
				(width 0.1)
				(type default)
			)
			(layer "F.Fab")
		)
		(fp_line
			(start -0.32512 0.175006)
			(end -0.32512 -0.175006)
			(stroke
				(width 0.1)
				(type default)
			)
			(layer "F.Fab")
		)
		(fp_line
			(start -0.32512 -0.175006)
			(end 0.32512 -0.175006)
			(stroke
				(width 0.1)
				(type default)
			)
			(layer "F.Fab")
		)
		(pad "1" smd rect
			(at -0.2667 0 180)
			(size 0.3048 0.381)
			(layers "F.Cu" "F.Mask" "F.Paste")
			(net "RT_CPU0_P2_ADDR2")
		)
		(pad "2" smd rect
			(at 0.2667 0)
			(size 0.3048 0.381)
			(layers "F.Cu" "F.Mask" "F.Paste")
			(net "GND")
		)
	)
	(footprint ""
		(layer "F.Cu")
		(at 197.269608 -115.657376)
		(property "Reference" "R4171"
			(at 0 0 0)
			(layer "F.SilkS")
			(hide yes)
			(effects
				(font
					(size 1.27 1.27)
				)
			)
		)
		(property "Value" ""
			(at 0 0 0)
			(layer "F.Fab")
			(effects
				(font
					(size 1.27 1.27)
				)
			)
		)
		(duplicate_pad_numbers_are_jumpers no)
		(fp_line
			(start -0.7874 -0.4064)
			(end 0.7874 -0.4064)
			(stroke
				(width 0.1524)
				(type default)
			)
			(layer "F.SilkS")
		)
		(fp_line
			(start -0.7874 0.4064)
			(end -0.7874 -0.4064)
			(stroke
				(width 0.1524)
				(type default)
			)
			(layer "F.SilkS")
		)
		(fp_line
			(start 0.7874 -0.4064)
			(end 0.7874 0.4064)
			(stroke
				(width 0.1524)
				(type default)
			)
			(layer "F.SilkS")
		)
		(fp_line
			(start 0.7874 0.4064)
			(end -0.7874 0.4064)
			(stroke
				(width 0.1524)
				(type default)
			)
			(layer "F.SilkS")
		)
		(fp_line
			(start -0.67945 -0.305054)
			(end -0.12065 -0.305054)
			(stroke
				(width 0.1)
				(type default)
			)
			(layer "F.Fab")
		)
		(fp_line
			(start -0.67945 0.3048)
			(end -0.67945 -0.305054)
			(stroke
				(width 0.1)
				(type default)
			)
			(layer "F.Fab")
		)
		(fp_line
			(start -0.12065 -0.305054)
			(end -0.12065 -0.2794)
			(stroke
				(width 0.1)
				(type default)
			)
			(layer "F.Fab")
		)
		(fp_line
			(start -0.12065 -0.2794)
			(end 0.12065 -0.2794)
			(stroke
				(width 0.1)
				(type default)
			)
			(layer "F.Fab")
		)
		(fp_line
			(start -0.12065 0.2794)
			(end -0.12065 0.3048)
			(stroke
				(width 0.1)
				(type default)
			)
			(layer "F.Fab")
		)
		(fp_line
			(start -0.12065 0.3048)
			(end -0.67945 0.3048)
			(stroke
				(width 0.1)
				(type default)
			)
			(layer "F.Fab")
		)
		(fp_line
			(start 0.120396 0.2794)
			(end -0.12065 0.2794)
			(stroke
				(width 0.1)
				(type default)
			)
			(layer "F.Fab")
		)
		(fp_line
			(start 0.120396 0.3048)
			(end 0.120396 0.2794)
			(stroke
				(width 0.1)
				(type default)
			)
			(layer "F.Fab")
		)
		(fp_line
			(start 0.12065 -0.3048)
			(end 0.67945 -0.3048)
			(stroke
				(width 0.1)
				(type default)
			)
			(layer "F.Fab")
		)
		(fp_line
			(start 0.12065 -0.2794)
			(end 0.12065 -0.3048)
			(stroke
				(width 0.1)
				(type default)
			)
			(layer "F.Fab")
		)
		(fp_line
			(start 0.67945 -0.3048)
			(end 0.67945 0.3048)
			(stroke
				(width 0.1)
				(type default)
			)
			(layer "F.Fab")
		)
		(fp_line
			(start 0.67945 0.3048)
			(end 0.120396 0.3048)
			(stroke
				(width 0.1)
				(type default)
			)
			(layer "F.Fab")
		)
		(pad "1" smd circle
			(at -0.40005 0)
			(size 0 0)
			(layers "F.Cu" "F.Mask" "F.Paste")
			(net "GPU_3V3IO_RSVD3_ISO_R")
		)
		(pad "2" smd circle
			(at 0.40005 0)
			(size 0 0)
			(layers "F.Cu" "F.Mask" "F.Paste")
			(net "GPU_3V3IO_RSVD3_ISO")
		)
	)
	(footprint ""
		(layer "F.Cu")
		(at 335.176876 -325.656448)
		(property "Reference" "PL10"
			(at -3.115056 -15.887446 0)
			(unlocked yes)
			(layer "F.SilkS")
			(effects
				(font
					(size 0.7874 0.5842)
					(thickness 0.1524)
				)
				(justify left)
			)
		)
		(property "Value" ""
			(at 0 0 0)
			(layer "F.Fab")
			(effects
				(font
					(size 1.27 1.27)
				)
			)
		)
		(duplicate_pad_numbers_are_jumpers no)
		(fp_line
			(start -3.750056 -5.500116)
			(end -2.393442 -5.500116)
			(stroke
				(width 0.1524)
				(type default)
			)
			(layer "F.SilkS")
		)
		(fp_line
			(start -3.750056 5.500116)
			(end -3.750056 -5.500116)
			(stroke
				(width 0.1524)
				(type default)
			)
			(layer "F.SilkS")
		)
		(fp_line
			(start -2.393442 5.500116)
			(end -3.750056 5.500116)
			(stroke
				(width 0.1524)
				(type default)
			)
			(layer "F.SilkS")
		)
		(fp_line
			(start 2.393442 5.500116)
			(end 3.750056 5.500116)
			(stroke
				(width 0.1524)
				(type default)
			)
			(layer "F.SilkS")
		)
		(fp_line
			(start 3.750056 -5.500116)
			(end 2.393442 -5.500116)
			(stroke
				(width 0.1524)
				(type default)
			)
			(layer "F.SilkS")
		)
		(fp_line
			(start 3.750056 5.500116)
			(end 3.750056 -5.500116)
			(stroke
				(width 0.1524)
				(type default)
			)
			(layer "F.SilkS")
		)
		(fp_poly
			(pts
				(xy -3.9116 -4.249928) (xy -4.3434 -4.034028) (xy -4.3434 -4.465828)
			)
			(stroke
				(width 0)
				(type default)
			)
			(fill yes)
			(layer "F.SilkS")
		)
		(fp_line
			(start -3.750056 -5.500116)
			(end -3.750056 5.500116)
			(stroke
				(width 0.1)
				(type default)
			)
			(layer "F.Fab")
		)
		(fp_line
			(start -3.750056 5.500116)
			(end 3.750056 5.500116)
			(stroke
				(width 0.1)
				(type default)
			)
			(layer "F.Fab")
		)
		(fp_line
			(start 3.750056 -5.500116)
			(end -3.750056 -5.500116)
			(stroke
				(width 0.1)
				(type default)
			)
			(layer "F.Fab")
		)
		(fp_line
			(start 3.750056 5.500116)
			(end 3.750056 -5.500116)
			(stroke
				(width 0.1)
				(type default)
			)
			(layer "F.Fab")
		)
		(fp_poly
			(pts
				(xy -4.9276 -4.757928) (xy -4.9276 -3.741928) (xy -3.9116 -4.249928)
			)
			(stroke
				(width 0)
				(type default)
			)
			(fill yes)
			(layer "F.Fab")
		)
		(pad "1" smd rect
			(at 0 -4.249928 270)
			(size 2.413 4.5212)
			(layers "F.Cu" "F.Mask" "F.Paste")
			(net "SW_PVDDCR_CPU1_P0_SW1")
		)
		(pad "2" smd rect
			(at 0 -1.175004 270)
			(size 1.3716 4.5212)
			(layers "F.Cu" "F.Mask" "F.Paste")
			(net "IND_CPU1_P0_CPL5")
		)
		(pad "3" smd rect
			(at 0 1.175004 270)
			(size 1.3716 4.5212)
			(layers "F.Cu" "F.Mask" "F.Paste")
			(net "IND_CPU1_P0_CPL1")
		)
		(pad "4" smd rect
			(at 0 4.249928 270)
			(size 2.413 4.5212)
			(layers "F.Cu" "F.Mask" "F.Paste")
			(net "PVDDCR_CPU1_P0")
		)
	)
	(footprint ""
		(layer "F.Cu")
		(at 303.323498 -429.2219 180)
		(property "Reference" "R4577"
			(at 0 0 180)
			(layer "F.SilkS")
			(hide yes)
			(effects
				(font
					(size 1.27 1.27)
				)
			)
		)
		(property "Value" ""
			(at 0 0 180)
			(layer "F.Fab")
			(effects
				(font
					(size 1.27 1.27)
				)
			)
		)
		(duplicate_pad_numbers_are_jumpers no)
		(fp_line
			(start 0.7874 0.4064)
			(end -0.7874 0.4064)
			(stroke
				(width 0.1524)
				(type default)
			)
			(layer "F.SilkS")
		)
		(fp_line
			(start 0.7874 -0.4064)
			(end 0.7874 0.4064)
			(stroke
				(width 0.1524)
				(type default)
			)
			(layer "F.SilkS")
		)
		(fp_line
			(start -0.7874 0.4064)
			(end -0.7874 -0.4064)
			(stroke
				(width 0.1524)
				(type default)
			)
			(layer "F.SilkS")
		)
		(fp_line
			(start -0.7874 -0.4064)
			(end 0.7874 -0.4064)
			(stroke
				(width 0.1524)
				(type default)
			)
			(layer "F.SilkS")
		)
		(fp_line
			(start 0.67945 0.3048)
			(end 0.120396 0.3048)
			(stroke
				(width 0.1)
				(type default)
			)
			(layer "F.Fab")
		)
		(fp_line
			(start 0.67945 -0.3048)
			(end 0.67945 0.3048)
			(stroke
				(width 0.1)
				(type default)
			)
			(layer "F.Fab")
		)
		(fp_line
			(start 0.12065 -0.2794)
			(end 0.12065 -0.3048)
			(stroke
				(width 0.1)
				(type default)
			)
			(layer "F.Fab")
		)
		(fp_line
			(start 0.12065 -0.3048)
			(end 0.67945 -0.3048)
			(stroke
				(width 0.1)
				(type default)
			)
			(layer "F.Fab")
		)
		(fp_line
			(start 0.120396 0.3048)
			(end 0.120396 0.2794)
			(stroke
				(width 0.1)
				(type default)
			)
			(layer "F.Fab")
		)
		(fp_line
			(start 0.120396 0.2794)
			(end -0.12065 0.2794)
			(stroke
				(width 0.1)
				(type default)
			)
			(layer "F.Fab")
		)
		(fp_line
			(start -0.12065 0.3048)
			(end -0.67945 0.3048)
			(stroke
				(width 0.1)
				(type default)
			)
			(layer "F.Fab")
		)
		(fp_line
			(start -0.12065 0.2794)
			(end -0.12065 0.3048)
			(stroke
				(width 0.1)
				(type default)
			)
			(layer "F.Fab")
		)
		(fp_line
			(start -0.12065 -0.2794)
			(end 0.12065 -0.2794)
			(stroke
				(width 0.1)
				(type default)
			)
			(layer "F.Fab")
		)
		(fp_line
			(start -0.12065 -0.305054)
			(end -0.12065 -0.2794)
			(stroke
				(width 0.1)
				(type default)
			)
			(layer "F.Fab")
		)
		(fp_line
			(start -0.67945 0.3048)
			(end -0.67945 -0.305054)
			(stroke
				(width 0.1)
				(type default)
			)
			(layer "F.Fab")
		)
		(fp_line
			(start -0.67945 -0.305054)
			(end -0.12065 -0.305054)
			(stroke
				(width 0.1)
				(type default)
			)
			(layer "F.Fab")
		)
		(pad "1" smd circle
			(at -0.40005 0 180)
			(size 0 0)
			(layers "F.Cu" "F.Mask" "F.Paste")
			(net "GPU_3V3IO_RSVD3_FFU")
		)
		(pad "2" smd circle
			(at 0.40005 0 180)
			(size 0 0)
			(layers "F.Cu" "F.Mask" "F.Paste")
			(net "GPU_3V3IO_RSVD3_FFU_ISO")
		)
	)
)
